(kicad_pcb
	(version 20260206)
	(generator "pcbnew")
	(generator_version "10.0")
	(general
		(thickness 1.6)
		(legacy_teardrops no)
	)
	(paper "A4")
	(title_block
		(title "04192023_DAF0TMB3IC0_F0TG_MB_C_brd_V02_OCP.brd")
		(comment 1 "Grand Teton / footprint 4248 of 8354 (J33), pads 114-226 of 291")
	)
	(layers
		(0 "F.Cu" signal "TOP")
		(4 "In1.Cu" signal "GND")
		(6 "In2.Cu" signal "IN1")
		(8 "In3.Cu" signal "GND1")
		(10 "In4.Cu" signal "IN2")
		(12 "In5.Cu" signal "GND2")
		(14 "In6.Cu" signal "IN3")
		(16 "In7.Cu" signal "GND3")
		(18 "In8.Cu" signal "VCC")
		(20 "In9.Cu" signal "VCC1")
		(22 "In10.Cu" signal "GND4")
		(24 "In11.Cu" signal "IN4")
		(26 "In12.Cu" signal "GND5")
		(28 "In13.Cu" signal "IN5")
		(30 "In14.Cu" signal "GND6")
		(32 "In15.Cu" signal "IN6")
		(34 "In16.Cu" signal "GND7")
		(2 "B.Cu" signal "BOTTOM")
		(9 "F.Adhes" user "F.Adhesive")
		(11 "B.Adhes" user "B.Adhesive")
		(13 "F.Paste" user "Package Geometry/Pastemask Top")
		(15 "B.Paste" user "Package Geometry/Pastemask Bottom")
		(5 "F.SilkS" user "Ref Des/Silkscreen Top")
		(7 "B.SilkS" user "Ref Des/Silkscreen Bottom")
		(1 "F.Mask" user "Board Geometry/Soldermask Top")
		(3 "B.Mask" user "Board Geometry/Soldermask Bottom")
		(17 "Dwgs.User" user "User.Drawings")
		(19 "Cmts.User" user "User.Comments")
		(21 "Eco1.User" user "User.Eco1")
		(23 "Eco2.User" user "User.Eco2")
		(25 "Edge.Cuts" user "Board Geometry/Outline")
		(27 "Margin" user)
		(31 "F.CrtYd" user "Package Geometry/Place Bound Top")
		(29 "B.CrtYd" user "Package Geometry/Place Bound Bottom")
		(35 "F.Fab" user "Ref Des/Assembly Top")
		(33 "B.Fab" user "Ref Des/Assembly Bottom")
	)
	(footprint ""
		(layer "F.Cu")
		(at 19.658076 -255.560322 180)
		(property "Reference" "J33"
			(at -1.25984 -82.079846 0)
			(unlocked yes)
			(layer "F.SilkS")
			(effects
				(font
					(size 0.7874 0.5842)
					(thickness 0.1524)
				)
			)
		)
		(property "Value" ""
			(at 0 0 180)
			(layer "F.Fab")
			(effects
				(font
					(size 1.27 1.27)
				)
			)
		)
		(duplicate_pad_numbers_are_jumpers no)
		(pad "114" smd rect
			(at -2.050034 37.824918 90)
			(size 0.519938 1.4986)
			(layers "F.Cu" "F.Mask" "F.Paste")
			(net "GND")
		)
		(pad "115" smd rect
			(at -2.050034 38.675056 90)
			(size 0.519938 1.4986)
			(layers "F.Cu" "F.Mask" "F.Paste")
			(net "M_F_CPU1_SB_DQS_DP<1>")
		)
		(pad "116" smd rect
			(at -2.050034 39.52494 90)
			(size 0.519938 1.4986)
			(layers "F.Cu" "F.Mask" "F.Paste")
			(net "M_F_CPU1_SB_DQS_DN<1>")
		)
		(pad "117" smd rect
			(at -2.050034 40.375078 90)
			(size 0.519938 1.4986)
			(layers "F.Cu" "F.Mask" "F.Paste")
			(net "GND")
		)
		(pad "118" smd rect
			(at -2.050034 41.224962 90)
			(size 0.519938 1.4986)
			(layers "F.Cu" "F.Mask" "F.Paste")
			(net "M_F_CPU1_SB_DQ<12>")
		)
		(pad "119" smd rect
			(at -2.050034 42.0751 90)
			(size 0.519938 1.4986)
			(layers "F.Cu" "F.Mask" "F.Paste")
			(net "GND")
		)
		(pad "120" smd rect
			(at -2.050034 42.924984 90)
			(size 0.519938 1.4986)
			(layers "F.Cu" "F.Mask" "F.Paste")
			(net "M_F_CPU1_SB_DQ<13>")
		)
		(pad "121" smd rect
			(at -2.050034 43.775122 90)
			(size 0.519938 1.4986)
			(layers "F.Cu" "F.Mask" "F.Paste")
			(net "GND")
		)
		(pad "122" smd rect
			(at -2.050034 44.625006 90)
			(size 0.519938 1.4986)
			(layers "F.Cu" "F.Mask" "F.Paste")
			(net "M_F_CPU1_SB_DQ<16>")
		)
		(pad "123" smd rect
			(at -2.050034 45.47489 90)
			(size 0.519938 1.4986)
			(layers "F.Cu" "F.Mask" "F.Paste")
			(net "GND")
		)
		(pad "124" smd rect
			(at -2.050034 46.325028 90)
			(size 0.519938 1.4986)
			(layers "F.Cu" "F.Mask" "F.Paste")
			(net "M_F_CPU1_SB_DQ<17>")
		)
		(pad "125" smd rect
			(at -2.050034 47.174912 90)
			(size 0.519938 1.4986)
			(layers "F.Cu" "F.Mask" "F.Paste")
			(net "GND")
		)
		(pad "126" smd rect
			(at -2.050034 48.02505 90)
			(size 0.519938 1.4986)
			(layers "F.Cu" "F.Mask" "F.Paste")
			(net "M_F_CPU1_SB_DQS_DP<2>")
		)
		(pad "127" smd rect
			(at -2.050034 48.874934 90)
			(size 0.519938 1.4986)
			(layers "F.Cu" "F.Mask" "F.Paste")
			(net "M_F_CPU1_SB_DQS_DN<2>")
		)
		(pad "128" smd rect
			(at -2.050034 49.725072 90)
			(size 0.519938 1.4986)
			(layers "F.Cu" "F.Mask" "F.Paste")
			(net "GND")
		)
		(pad "129" smd rect
			(at -2.050034 50.574956 90)
			(size 0.519938 1.4986)
			(layers "F.Cu" "F.Mask" "F.Paste")
			(net "M_F_CPU1_SB_DQ<20>")
		)
		(pad "130" smd rect
			(at -2.050034 51.425094 90)
			(size 0.519938 1.4986)
			(layers "F.Cu" "F.Mask" "F.Paste")
			(net "GND")
		)
		(pad "131" smd rect
			(at -2.050034 52.274978 90)
			(size 0.519938 1.4986)
			(layers "F.Cu" "F.Mask" "F.Paste")
			(net "M_F_CPU1_SB_DQ<21>")
		)
		(pad "132" smd rect
			(at -2.050034 53.125116 90)
			(size 0.519938 1.4986)
			(layers "F.Cu" "F.Mask" "F.Paste")
			(net "GND")
		)
		(pad "133" smd rect
			(at -2.050034 53.975 90)
			(size 0.519938 1.4986)
			(layers "F.Cu" "F.Mask" "F.Paste")
			(net "M_F_CPU1_SB_DQ<24>")
		)
		(pad "134" smd rect
			(at -2.050034 54.824884 90)
			(size 0.519938 1.4986)
			(layers "F.Cu" "F.Mask" "F.Paste")
			(net "GND")
		)
		(pad "135" smd rect
			(at -2.050034 55.675022 90)
			(size 0.519938 1.4986)
			(layers "F.Cu" "F.Mask" "F.Paste")
			(net "M_F_CPU1_SB_DQ<25>")
		)
		(pad "136" smd rect
			(at -2.050034 56.524906 90)
			(size 0.519938 1.4986)
			(layers "F.Cu" "F.Mask" "F.Paste")
			(net "GND")
		)
		(pad "137" smd rect
			(at -2.050034 57.375044 90)
			(size 0.519938 1.4986)
			(layers "F.Cu" "F.Mask" "F.Paste")
			(net "M_F_CPU1_SB_DQS_DP<3>")
		)
		(pad "138" smd rect
			(at -2.050034 58.224928 90)
			(size 0.519938 1.4986)
			(layers "F.Cu" "F.Mask" "F.Paste")
			(net "M_F_CPU1_SB_DQS_DN<3>")
		)
		(pad "139" smd rect
			(at -2.050034 59.075066 90)
			(size 0.519938 1.4986)
			(layers "F.Cu" "F.Mask" "F.Paste")
			(net "GND")
		)
		(pad "140" smd rect
			(at -2.050034 59.92495 90)
			(size 0.519938 1.4986)
			(layers "F.Cu" "F.Mask" "F.Paste")
			(net "M_F_CPU1_SB_DQ<28>")
		)
		(pad "141" smd rect
			(at -2.050034 60.775088 90)
			(size 0.519938 1.4986)
			(layers "F.Cu" "F.Mask" "F.Paste")
			(net "GND")
		)
		(pad "142" smd rect
			(at -2.050034 61.624972 90)
			(size 0.519938 1.4986)
			(layers "F.Cu" "F.Mask" "F.Paste")
			(net "M_F_CPU1_SB_DQ<29>")
		)
		(pad "143" smd rect
			(at -2.050034 62.47511 90)
			(size 0.519938 1.4986)
			(layers "F.Cu" "F.Mask" "F.Paste")
			(net "GND")
		)
		(pad "144" smd rect
			(at -2.050034 63.324994 90)
			(size 0.519938 1.4986)
			(layers "F.Cu" "F.Mask" "F.Paste")
			(net "Net_2327")
		)
		(pad "145" smd rect
			(at 2.050034 -63.324994 90)
			(size 0.519938 1.4986)
			(layers "F.Cu" "F.Mask" "F.Paste")
			(net "P12V_MEM_CPU1")
		)
		(pad "146" smd rect
			(at 2.050034 -62.47511 90)
			(size 0.519938 1.4986)
			(layers "F.Cu" "F.Mask" "F.Paste")
			(net "P12V_MEM_CPU1")
		)
		(pad "147" smd rect
			(at 2.050034 -61.624972 90)
			(size 0.519938 1.4986)
			(layers "F.Cu" "F.Mask" "F.Paste")
			(net "PWRGD_CHF_CPU1_DIMM")
		)
		(pad "148" smd rect
			(at 2.050034 -60.775088 90)
			(size 0.519938 1.4986)
			(layers "F.Cu" "F.Mask" "F.Paste")
			(net "PD_CHF_CPU1_DIMM_SAA")
		)
		(pad "149" smd rect
			(at 2.050034 -59.92495 90)
			(size 0.519938 1.4986)
			(layers "F.Cu" "F.Mask" "F.Paste")
			(net "Net_2328")
		)
		(pad "150" smd rect
			(at 2.050034 -59.075066 90)
			(size 0.519938 1.4986)
			(layers "F.Cu" "F.Mask" "F.Paste")
			(net "Net_2329")
		)
		(pad "151" smd rect
			(at 2.050034 -58.224928 90)
			(size 0.519938 1.4986)
			(layers "F.Cu" "F.Mask" "F.Paste")
			(net "GND")
		)
		(pad "152" smd rect
			(at 2.050034 -57.375044 90)
			(size 0.519938 1.4986)
			(layers "F.Cu" "F.Mask" "F.Paste")
			(net "M_F_CPU1_SA_DQ<2>")
		)
		(pad "153" smd rect
			(at 2.050034 -56.524906 90)
			(size 0.519938 1.4986)
			(layers "F.Cu" "F.Mask" "F.Paste")
			(net "GND")
		)
		(pad "154" smd rect
			(at 2.050034 -55.675022 90)
			(size 0.519938 1.4986)
			(layers "F.Cu" "F.Mask" "F.Paste")
			(net "M_F_CPU1_SA_DQ<3>")
		)
		(pad "155" smd rect
			(at 2.050034 -54.824884 90)
			(size 0.519938 1.4986)
			(layers "F.Cu" "F.Mask" "F.Paste")
			(net "GND")
		)
		(pad "156" smd rect
			(at 2.050034 -53.975 90)
			(size 0.519938 1.4986)
			(layers "F.Cu" "F.Mask" "F.Paste")
			(net "M_F_CPU1_SA_DQS_DN<5>")
		)
		(pad "157" smd rect
			(at 2.050034 -53.125116 90)
			(size 0.519938 1.4986)
			(layers "F.Cu" "F.Mask" "F.Paste")
			(net "M_F_CPU1_SA_DQS_DP<5>")
		)
		(pad "158" smd rect
			(at 2.050034 -52.274978 90)
			(size 0.519938 1.4986)
			(layers "F.Cu" "F.Mask" "F.Paste")
			(net "GND")
		)
		(pad "159" smd rect
			(at 2.050034 -51.425094 90)
			(size 0.519938 1.4986)
			(layers "F.Cu" "F.Mask" "F.Paste")
			(net "M_F_CPU1_SA_DQ<6>")
		)
		(pad "160" smd rect
			(at 2.050034 -50.574956 90)
			(size 0.519938 1.4986)
			(layers "F.Cu" "F.Mask" "F.Paste")
			(net "GND")
		)
		(pad "161" smd rect
			(at 2.050034 -49.725072 90)
			(size 0.519938 1.4986)
			(layers "F.Cu" "F.Mask" "F.Paste")
			(net "M_F_CPU1_SA_DQ<7>")
		)
		(pad "162" smd rect
			(at 2.050034 -48.874934 90)
			(size 0.519938 1.4986)
			(layers "F.Cu" "F.Mask" "F.Paste")
			(net "GND")
		)
		(pad "163" smd rect
			(at 2.050034 -48.02505 90)
			(size 0.519938 1.4986)
			(layers "F.Cu" "F.Mask" "F.Paste")
			(net "M_F_CPU1_SA_DQ<10>")
		)
		(pad "164" smd rect
			(at 2.050034 -47.174912 90)
			(size 0.519938 1.4986)
			(layers "F.Cu" "F.Mask" "F.Paste")
			(net "GND")
		)
		(pad "165" smd rect
			(at 2.050034 -46.325028 90)
			(size 0.519938 1.4986)
			(layers "F.Cu" "F.Mask" "F.Paste")
			(net "M_F_CPU1_SA_DQ<11>")
		)
		(pad "166" smd rect
			(at 2.050034 -45.47489 90)
			(size 0.519938 1.4986)
			(layers "F.Cu" "F.Mask" "F.Paste")
			(net "GND")
		)
		(pad "167" smd rect
			(at 2.050034 -44.625006 90)
			(size 0.519938 1.4986)
			(layers "F.Cu" "F.Mask" "F.Paste")
			(net "M_F_CPU1_SA_DQS_DN<6>")
		)
		(pad "168" smd rect
			(at 2.050034 -43.775122 90)
			(size 0.519938 1.4986)
			(layers "F.Cu" "F.Mask" "F.Paste")
			(net "M_F_CPU1_SA_DQS_DP<6>")
		)
		(pad "169" smd rect
			(at 2.050034 -42.924984 90)
			(size 0.519938 1.4986)
			(layers "F.Cu" "F.Mask" "F.Paste")
			(net "GND")
		)
		(pad "170" smd rect
			(at 2.050034 -42.0751 90)
			(size 0.519938 1.4986)
			(layers "F.Cu" "F.Mask" "F.Paste")
			(net "M_F_CPU1_SA_DQ<14>")
		)
		(pad "171" smd rect
			(at 2.050034 -41.224962 90)
			(size 0.519938 1.4986)
			(layers "F.Cu" "F.Mask" "F.Paste")
			(net "GND")
		)
		(pad "172" smd rect
			(at 2.050034 -40.375078 90)
			(size 0.519938 1.4986)
			(layers "F.Cu" "F.Mask" "F.Paste")
			(net "M_F_CPU1_SA_DQ<15>")
		)
		(pad "173" smd rect
			(at 2.050034 -39.52494 90)
			(size 0.519938 1.4986)
			(layers "F.Cu" "F.Mask" "F.Paste")
			(net "GND")
		)
		(pad "174" smd rect
			(at 2.050034 -38.675056 90)
			(size 0.519938 1.4986)
			(layers "F.Cu" "F.Mask" "F.Paste")
			(net "M_F_CPU1_SA_DQ<18>")
		)
		(pad "175" smd rect
			(at 2.050034 -37.824918 90)
			(size 0.519938 1.4986)
			(layers "F.Cu" "F.Mask" "F.Paste")
			(net "GND")
		)
		(pad "176" smd rect
			(at 2.050034 -36.975034 90)
			(size 0.519938 1.4986)
			(layers "F.Cu" "F.Mask" "F.Paste")
			(net "M_F_CPU1_SA_DQ<19>")
		)
		(pad "177" smd rect
			(at 2.050034 -36.124896 90)
			(size 0.519938 1.4986)
			(layers "F.Cu" "F.Mask" "F.Paste")
			(net "GND")
		)
		(pad "178" smd rect
			(at 2.050034 -35.275012 90)
			(size 0.519938 1.4986)
			(layers "F.Cu" "F.Mask" "F.Paste")
			(net "M_F_CPU1_SA_DQS_DN<7>")
		)
		(pad "179" smd rect
			(at 2.050034 -34.425128 90)
			(size 0.519938 1.4986)
			(layers "F.Cu" "F.Mask" "F.Paste")
			(net "M_F_CPU1_SA_DQS_DP<7>")
		)
		(pad "180" smd rect
			(at 2.050034 -33.57499 90)
			(size 0.519938 1.4986)
			(layers "F.Cu" "F.Mask" "F.Paste")
			(net "GND")
		)
		(pad "181" smd rect
			(at 2.050034 -32.725106 90)
			(size 0.519938 1.4986)
			(layers "F.Cu" "F.Mask" "F.Paste")
			(net "M_F_CPU1_SA_DQ<22>")
		)
		(pad "182" smd rect
			(at 2.050034 -31.874968 90)
			(size 0.519938 1.4986)
			(layers "F.Cu" "F.Mask" "F.Paste")
			(net "GND")
		)
		(pad "183" smd rect
			(at 2.050034 -31.025084 90)
			(size 0.519938 1.4986)
			(layers "F.Cu" "F.Mask" "F.Paste")
			(net "M_F_CPU1_SA_DQ<23>")
		)
		(pad "184" smd rect
			(at 2.050034 -30.174946 90)
			(size 0.519938 1.4986)
			(layers "F.Cu" "F.Mask" "F.Paste")
			(net "GND")
		)
		(pad "185" smd rect
			(at 2.050034 -29.325062 90)
			(size 0.519938 1.4986)
			(layers "F.Cu" "F.Mask" "F.Paste")
			(net "M_F_CPU1_SA_DQ<26>")
		)
		(pad "186" smd rect
			(at 2.050034 -28.474924 90)
			(size 0.519938 1.4986)
			(layers "F.Cu" "F.Mask" "F.Paste")
			(net "GND")
		)
		(pad "187" smd rect
			(at 2.050034 -27.62504 90)
			(size 0.519938 1.4986)
			(layers "F.Cu" "F.Mask" "F.Paste")
			(net "M_F_CPU1_SA_DQ<27>")
		)
		(pad "188" smd rect
			(at 2.050034 -26.774902 90)
			(size 0.519938 1.4986)
			(layers "F.Cu" "F.Mask" "F.Paste")
			(net "GND")
		)
		(pad "189" smd rect
			(at 2.050034 -25.925018 90)
			(size 0.519938 1.4986)
			(layers "F.Cu" "F.Mask" "F.Paste")
			(net "M_F_CPU1_SA_DQS_DN<8>")
		)
		(pad "190" smd rect
			(at 2.050034 -25.07488 90)
			(size 0.519938 1.4986)
			(layers "F.Cu" "F.Mask" "F.Paste")
			(net "M_F_CPU1_SA_DQS_DP<8>")
		)
		(pad "191" smd rect
			(at 2.050034 -24.224996 90)
			(size 0.519938 1.4986)
			(layers "F.Cu" "F.Mask" "F.Paste")
			(net "GND")
		)
		(pad "192" smd rect
			(at 2.050034 -23.375112 90)
			(size 0.519938 1.4986)
			(layers "F.Cu" "F.Mask" "F.Paste")
			(net "M_F_CPU1_SA_DQ<30>")
		)
		(pad "193" smd rect
			(at 2.050034 -22.524974 90)
			(size 0.519938 1.4986)
			(layers "F.Cu" "F.Mask" "F.Paste")
			(net "GND")
		)
		(pad "194" smd rect
			(at 2.050034 -21.67509 90)
			(size 0.519938 1.4986)
			(layers "F.Cu" "F.Mask" "F.Paste")
			(net "M_F_CPU1_SA_DQ<31>")
		)
		(pad "195" smd rect
			(at 2.050034 -20.824952 90)
			(size 0.519938 1.4986)
			(layers "F.Cu" "F.Mask" "F.Paste")
			(net "GND")
		)
		(pad "196" smd rect
			(at 2.050034 -19.975068 90)
			(size 0.519938 1.4986)
			(layers "F.Cu" "F.Mask" "F.Paste")
			(net "M_F_CPU1_SA_CB<2>")
		)
		(pad "197" smd rect
			(at 2.050034 -19.12493 90)
			(size 0.519938 1.4986)
			(layers "F.Cu" "F.Mask" "F.Paste")
			(net "GND")
		)
		(pad "198" smd rect
			(at 2.050034 -18.275046 90)
			(size 0.519938 1.4986)
			(layers "F.Cu" "F.Mask" "F.Paste")
			(net "M_F_CPU1_SA_CB<3>")
		)
		(pad "199" smd rect
			(at 2.050034 -17.424908 90)
			(size 0.519938 1.4986)
			(layers "F.Cu" "F.Mask" "F.Paste")
			(net "GND")
		)
		(pad "200" smd rect
			(at 2.050034 -16.575024 90)
			(size 0.519938 1.4986)
			(layers "F.Cu" "F.Mask" "F.Paste")
			(net "M_F_CPU1_SA_DQS_DN<9>")
		)
		(pad "201" smd rect
			(at 2.050034 -15.724886 90)
			(size 0.519938 1.4986)
			(layers "F.Cu" "F.Mask" "F.Paste")
			(net "M_F_CPU1_SA_DQS_DP<9>")
		)
		(pad "202" smd rect
			(at 2.050034 -14.875002 90)
			(size 0.519938 1.4986)
			(layers "F.Cu" "F.Mask" "F.Paste")
			(net "GND")
		)
		(pad "203" smd rect
			(at 2.050034 -14.025118 90)
			(size 0.519938 1.4986)
			(layers "F.Cu" "F.Mask" "F.Paste")
			(net "M_F_CPU1_SA_CB<6>")
		)
		(pad "204" smd rect
			(at 2.050034 -13.17498 90)
			(size 0.519938 1.4986)
			(layers "F.Cu" "F.Mask" "F.Paste")
			(net "GND")
		)
		(pad "205" smd rect
			(at 2.050034 -12.325096 90)
			(size 0.519938 1.4986)
			(layers "F.Cu" "F.Mask" "F.Paste")
			(net "M_F_CPU1_SA_CB<7>")
		)
		(pad "206" smd rect
			(at 2.050034 -11.474958 90)
			(size 0.519938 1.4986)
			(layers "F.Cu" "F.Mask" "F.Paste")
			(net "GND")
		)
		(pad "207" smd rect
			(at 2.050034 -10.625074 90)
			(size 0.519938 1.4986)
			(layers "F.Cu" "F.Mask" "F.Paste")
			(net "M_F_CPU1_RESET_N")
		)
		(pad "208" smd rect
			(at 2.050034 -9.774936 90)
			(size 0.519938 1.4986)
			(layers "F.Cu" "F.Mask" "F.Paste")
			(net "GND")
		)
		(pad "209" smd rect
			(at 2.050034 -8.925052 90)
			(size 0.519938 1.4986)
			(layers "F.Cu" "F.Mask" "F.Paste")
			(net "M_F_CPU1_SA_CS_N<1>")
		)
		(pad "210" smd rect
			(at 2.050034 -8.074914 90)
			(size 0.519938 1.4986)
			(layers "F.Cu" "F.Mask" "F.Paste")
			(net "GND")
		)
		(pad "211" smd rect
			(at 2.050034 -7.22503 90)
			(size 0.519938 1.4986)
			(layers "F.Cu" "F.Mask" "F.Paste")
			(net "M_F_CPU1_SA_CA<1>")
		)
		(pad "212" smd rect
			(at 2.050034 -6.374892 90)
			(size 0.519938 1.4986)
			(layers "F.Cu" "F.Mask" "F.Paste")
			(net "GND")
		)
		(pad "213" smd rect
			(at 2.050034 -5.525008 90)
			(size 0.519938 1.4986)
			(layers "F.Cu" "F.Mask" "F.Paste")
			(net "M_F_CPU1_SA_CA<3>")
		)
		(pad "214" smd rect
			(at 2.050034 -4.675124 90)
			(size 0.519938 1.4986)
			(layers "F.Cu" "F.Mask" "F.Paste")
			(net "GND")
		)
		(pad "215" smd rect
			(at 2.050034 -3.824986 90)
			(size 0.519938 1.4986)
			(layers "F.Cu" "F.Mask" "F.Paste")
			(net "M_F_CPU1_SA_CA<5>")
		)
		(pad "216" smd rect
			(at 2.050034 -2.975102 90)
			(size 0.519938 1.4986)
			(layers "F.Cu" "F.Mask" "F.Paste")
			(net "GND")
		)
		(pad "217" smd rect
			(at 2.050034 -2.124964 90)
			(size 0.519938 1.4986)
			(layers "F.Cu" "F.Mask" "F.Paste")
			(net "M_F_CPU1_CLK_DP<0>")
		)
		(pad "218" smd rect
			(at 2.050034 -1.27508 90)
			(size 0.519938 1.4986)
			(layers "F.Cu" "F.Mask" "F.Paste")
			(net "M_F_CPU1_CLK_DN<0>")
		)
		(pad "219" smd rect
			(at 2.050034 -0.424942 90)
			(size 0.519938 1.4986)
			(layers "F.Cu" "F.Mask" "F.Paste")
			(net "GND")
		)
		(pad "220" smd rect
			(at 2.050034 5.525008 90)
			(size 0.519938 1.4986)
			(layers "F.Cu" "F.Mask" "F.Paste")
			(net "Net_2330")
		)
		(pad "221" smd rect
			(at 2.050034 6.374892 90)
			(size 0.519938 1.4986)
			(layers "F.Cu" "F.Mask" "F.Paste")
			(net "M_F_CPU1_SB_CA<1>")
		)
		(pad "222" smd rect
			(at 2.050034 7.22503 90)
			(size 0.519938 1.4986)
			(layers "F.Cu" "F.Mask" "F.Paste")
			(net "GND")
		)
		(pad "223" smd rect
			(at 2.050034 8.074914 90)
			(size 0.519938 1.4986)
			(layers "F.Cu" "F.Mask" "F.Paste")
			(net "M_F_CPU1_SB_CA<3>")
		)
		(pad "224" smd rect
			(at 2.050034 8.925052 90)
			(size 0.519938 1.4986)
			(layers "F.Cu" "F.Mask" "F.Paste")
			(net "GND")
		)
		(pad "225" smd rect
			(at 2.050034 9.774936 90)
			(size 0.519938 1.4986)
			(layers "F.Cu" "F.Mask" "F.Paste")
			(net "M_F_CPU1_SB_CA<5>")
		)
		(pad "226" smd rect
			(at 2.050034 10.625074 90)
			(size 0.519938 1.4986)
			(layers "F.Cu" "F.Mask" "F.Paste")
			(net "GND")
		)
	)
)
